# S9S_MB_2U (Grand Teton) — schematic parts with pin connectivity, parts 1622–1622 of 6093; source: Cadence DE-HDL packaged netlist (pstxprt.dat, pstxnet.dat, pstchip.dat)

J29  SCONN288_ADR50017P130CC  SCONN288_ADR50017-P130CC IO  pkg DDR288S_1-1VXB  page 110
  1  VIN_BULK0  POWER  = P12V_S3_AUX_CPU1_NVDIMM
  2  RFU0  TRI  = TP_CHG_CPU1_DIMM1_FRU_0
  3  VIN_MGMT  POWER  = P3V3_AUX
  4  HSCL  IN  = I3C_SPD_DDREFGH_CPU1_LVC1_SCL_4
  5  HSDA  BI  = I3C_SPD_DDREFGH_CPU1_LVC1_SDA
  6  VSS0  POWER  = GND
  7  DQ0_A  BI  = M_G_CPU1_SA_DQ<0>
  8  VSS1  POWER  = GND
  9  DQ1_A  BI  = M_G_CPU1_SA_DQ<1>
  10  VSS2  POWER  = GND
  11  DQS0_A_T  BI  = M_G_CPU1_SA_DQS_DP<0>
  12  DQS0_A_C  BI  = M_G_CPU1_SA_DQS_DN<0>
  13  VSS3  POWER  = GND
  14  DQ4_A  BI  = M_G_CPU1_SA_DQ<4>
  15  VSS4  POWER  = GND
  16  DQ5_A  BI  = M_G_CPU1_SA_DQ<5>
  17  VSS5  POWER  = GND
  18  DQ8_A  BI  = M_G_CPU1_SA_DQ<8>
  19  VSS6  POWER  = GND
  20  DQ9_A  BI  = M_G_CPU1_SA_DQ<9>
  21  VSS7  POWER  = GND
  22  DQS1_A_T  BI  = M_G_CPU1_SA_DQS_DP<1>
  23  DQS1_A_C  BI  = M_G_CPU1_SA_DQS_DN<1>
  24  VSS8  POWER  = GND
  25  DQ12_A  BI  = M_G_CPU1_SA_DQ<12>
  26  VSS9  POWER  = GND
  27  DQ13_A  BI  = M_G_CPU1_SA_DQ<13>
  28  VSS10  POWER  = GND
  29  DQ16_A  BI  = M_G_CPU1_SA_DQ<16>
  30  VSS11  POWER  = GND
  31  DQ17_A  BI  = M_G_CPU1_SA_DQ<17>
  32  VSS12  POWER  = GND
  33  DQS2_A_T  BI  = M_G_CPU1_SA_DQS_DP<2>
  34  DQS2_A_C  BI  = M_G_CPU1_SA_DQS_DN<2>
  35  VSS13  POWER  = GND
  36  DQ20_A  BI  = M_G_CPU1_SA_DQ<20>
  37  VSS14  POWER  = GND
  38  DQ21_A  BI  = M_G_CPU1_SA_DQ<21>
  39  VSS15  POWER  = GND
  40  DQ24_A  BI  = M_G_CPU1_SA_DQ<24>
  41  VSS16  POWER  = GND
  42  DQ25_A  BI  = M_G_CPU1_SA_DQ<25>
  43  VSS17  POWER  = GND
  44  DQS3_A_T  BI  = M_G_CPU1_SA_DQS_DP<3>
  45  DQS3_A_C  BI  = M_G_CPU1_SA_DQS_DN<3>
  46  VSS18  POWER  = GND
  47  DQ28_A  BI  = M_G_CPU1_SA_DQ<28>
  48  VSS19  POWER  = GND
  49  DQ29_A  BI  = M_G_CPU1_SA_DQ<29>
  50  VSS20  POWER  = GND
  51  CB0_A  BI  = M_G_CPU1_SA_CB<0>
  52  VSS21  POWER  = GND
  53  CB1_A  BI  = M_G_CPU1_SA_CB<1>
  54  VSS22  POWER  = GND
  55  DQS4_A_T  BI  = M_G_CPU1_SA_DQS_DP<4>
  56  DQS4_A_C  BI  = M_G_CPU1_SA_DQS_DN<4>
  57  VSS23  POWER  = GND
  58  CB4_A  BI  = M_G_CPU1_SA_CB<4>
  59  VSS24  POWER  = GND
  60  CB5_A  BI  = M_G_CPU1_SA_CB<5>
  61  VSS25  POWER  = GND
  62  ALERT_N  OUT  = M_G_CPU1_ALERT_N
  63  VSS26  POWER  = GND
  64  CS0_A_N  IN  = M_G_CPU1_SA_CS_N<0>
  65  VSS27  POWER  = GND
  66  CA0_A  IN  = M_G_CPU1_SA_CA<0>
  67  VSS28  POWER  = GND
  68  CA2_A  IN  = M_G_CPU1_SA_CA<2>
  69  VSS29  POWER  = GND
  70  CA4_A  IN  = M_G_CPU1_SA_CA<4>
  71  VSS30  POWER  = GND
  72  CA6_A  IN  = M_G_CPU1_SA_CA<6>
  73  VSS31  POWER  = GND
  74  PAR_A  IN  = M_G_CPU1_SA_PAR
  75  VSS32  POWER  = GND
  76  CA0_B  IN  = M_G_CPU1_SB_CA<0>
  77  VSS33  POWER  = GND
  78  CA2_B  IN  = M_G_CPU1_SB_CA<2>
  79  VSS34  POWER  = GND
  80  CA4_B  IN  = M_G_CPU1_SB_CA<4>
  81  VSS35  POWER  = GND
  82  CA6_B  IN  = M_G_CPU1_SB_CA<6>
  83  VSS36  POWER  = GND
  84  CS0_B_N  IN  = M_G_CPU1_SB_CS_N<0>
  85  VSS37  POWER  = GND
  86  \lbd||rsp_a_n\  OUT  = M_G_CPU1_SA_RSP<0>
  87  \lbs||rsp_b_n\  OUT  = M_G_CPU1_SB_RSP<0>
  88  VSS38  POWER  = GND
  89  CB4_B  BI  = M_G_CPU1_SB_CB<4>
  90  VSS39  POWER  = GND
  91  CB5_B  BI  = M_G_CPU1_SB_CB<5>
  92  VSS40  POWER  = GND
  93  \dqs9_b_t||tdqs9_b_t||dbi4_b_n\  BI  = M_G_CPU1_SB_DQS_DP<9>
  94  \dqs9_b_c||tdqs9_b_c\  BI  = M_G_CPU1_SB_DQS_DN<9>
  95  VSS41  POWER  = GND
  96  CB0_B  BI  = M_G_CPU1_SB_CB<0>
  97  VSS42  POWER  = GND
  98  CB1_B  BI  = M_G_CPU1_SB_CB<1>
  99  VSS43  POWER  = GND
  100  DQ0_B  BI  = M_G_CPU1_SB_DQ<0>
  101  VSS44  POWER  = GND
  102  DQ1_B  BI  = M_G_CPU1_SB_DQ<1>
  103  VSS45  POWER  = GND
  104  DQS0_B_T  BI  = M_G_CPU1_SB_DQS_DP<0>
  105  DQS0_B_C  BI  = M_G_CPU1_SB_DQS_DN<0>
  106  VSS46  POWER  = GND
  107  DQ4_B  BI  = M_G_CPU1_SB_DQ<4>
  108  VSS47  POWER  = GND
  109  DQ5_B  BI  = M_G_CPU1_SB_DQ<5>
  110  VSS48  POWER  = GND
  111  DQ8_B  BI  = M_G_CPU1_SB_DQ<8>
  112  VSS49  POWER  = GND
  113  DQ9_B  BI  = M_G_CPU1_SB_DQ<9>
  114  VSS50  POWER  = GND
  115  DQS1_B_T  BI  = M_G_CPU1_SB_DQS_DP<1>
  116  DQS1_B_C  BI  = M_G_CPU1_SB_DQS_DN<1>
  117  VSS51  POWER  = GND
  118  DQ12_B  BI  = M_G_CPU1_SB_DQ<12>
  119  VSS52  POWER  = GND
  120  DQ13_B  BI  = M_G_CPU1_SB_DQ<13>
  121  VSS53  POWER  = GND
  122  DQ16_B  BI  = M_G_CPU1_SB_DQ<16>
  123  VSS54  POWER  = GND
  124  DQ17_B  BI  = M_G_CPU1_SB_DQ<17>
  125  VSS55  POWER  = GND
  126  DQS2_B_T  BI  = M_G_CPU1_SB_DQS_DP<2>
  127  DQS2_B_C  BI  = M_G_CPU1_SB_DQS_DN<2>
  128  VSS56  POWER  = GND
  129  DQ20_B  BI  = M_G_CPU1_SB_DQ<20>
  130  VSS57  POWER  = GND
  131  DQ21_B  BI  = M_G_CPU1_SB_DQ<21>
  132  VSS58  POWER  = GND
  133  DQ24_B  BI  = M_G_CPU1_SB_DQ<24>
  134  VSS59  POWER  = GND
  135  DQ25_B  BI  = M_G_CPU1_SB_DQ<25>
  136  VSS60  POWER  = GND
  137  DQS3_B_T  BI  = M_G_CPU1_SB_DQS_DP<3>
  138  DQS3_B_C  BI  = M_G_CPU1_SB_DQS_DN<3>
  139  VSS61  POWER  = GND
  140  DQ28_B  BI  = M_G_CPU1_SB_DQ<28>
  141  VSS62  POWER  = GND
  142  DQ29_B  BI  = M_G_CPU1_SB_DQ<29>
  143  VSS63  POWER  = GND
  144  RFU1  TRI  = TP_CHG_CPU1_DIMM1_FRU_1
  145  VIN_BULK1  POWER  = P12V_S3_AUX_CPU1_NVDIMM
  146  VIN_BULK2  POWER  = P12V_S3_AUX_CPU1_NVDIMM
  147  \pwr_good||fail_n\  BI  = PWRGD_CHG_CPU1_DIMM1
  148  HSA  IN  = PD_CHG_CPU1_DIMM1_SAA
  149  RFU2  TRI  = TP_CHG_CPU1_DIMM1_FRU_2
  150  RFU3  TRI  = TP_CHG_CPU1_DIMM1_FRU_3
  151  VSS64  POWER  = GND
  152  DQ2_A  BI  = M_G_CPU1_SA_DQ<2>
  153  VSS65  POWER  = GND
  154  DQ3_A  BI  = M_G_CPU1_SA_DQ<3>
  155  VSS66  POWER  = GND
  156  \dqs5_a_c||tdqs5_a_c||dqs5_a_t||tdqs5_a_t\  BI  = M_G_CPU1_SA_DQS_DN<5>
  157  \dqs5_a_t||tdqs5_a_t\  BI  = M_G_CPU1_SA_DQS_DP<5>
  158  VSS67  POWER  = GND
  159  DQ6_A  BI  = M_G_CPU1_SA_DQ<6>
  160  VSS68  POWER  = GND
  161  DQ7_A  BI  = M_G_CPU1_SA_DQ<7>
  162  VSS69  POWER  = GND
  163  DQ10_A  BI  = M_G_CPU1_SA_DQ<10>
  164  VSS70  POWER  = GND
  165  DQ11_A  BI  = M_G_CPU1_SA_DQ<11>
  166  VSS71  POWER  = GND
  167  \dqs6_a_c||tdqs6_a_c||dqs6_a_t||tdqs6_a_t\  BI  = M_G_CPU1_SA_DQS_DN<6>
  168  \dqs6_a_t||tdqs6_a_t\  BI  = M_G_CPU1_SA_DQS_DP<6>
  169  VSS72  POWER  = GND
  170  DQ14_A  BI  = M_G_CPU1_SA_DQ<14>
  171  VSS73  POWER  = GND
  172  DQ15_A  BI  = M_G_CPU1_SA_DQ<15>
  173  VSS74  POWER  = GND
  174  DQ18_A  BI  = M_G_CPU1_SA_DQ<18>
  175  VSS75  POWER  = GND
  176  DQ19_A  BI  = M_G_CPU1_SA_DQ<19>
  177  VSS76  POWER  = GND
  178  \dqs7_a_c||tdqs7_a_c\  BI  = M_G_CPU1_SA_DQS_DN<7>
  179  \dqs7_a_t||tdqs7_a_t\  BI  = M_G_CPU1_SA_DQS_DP<7>
  180  VSS77  POWER  = GND
  181  DQ22_A  BI  = M_G_CPU1_SA_DQ<22>
  182  VSS78  POWER  = GND
  183  DQ23_A  BI  = M_G_CPU1_SA_DQ<23>
  184  VSS79  POWER  = GND
  185  DQ26_A  BI  = M_G_CPU1_SA_DQ<26>
  186  VSS80  POWER  = GND
  187  DQ27_A  BI  = M_G_CPU1_SA_DQ<27>
  188  VSS81  POWER  = GND
  189  \dqs8_a_c||tdqs8_a_c\  BI  = M_G_CPU1_SA_DQS_DN<8>
  190  \dqs8_a_t||tdqs8_a_t\  BI  = M_G_CPU1_SA_DQS_DP<8>
  191  VSS82  POWER  = GND
  192  DQ30_A  BI  = M_G_CPU1_SA_DQ<30>
  193  VSS83  POWER  = GND
  194  DQ31_A  BI  = M_G_CPU1_SA_DQ<31>
  195  VSS84  POWER  = GND
  196  CB2_A  BI  = M_G_CPU1_SA_CB<2>
  197  VSS85  POWER  = GND
  198  CB3_A  BI  = M_G_CPU1_SA_CB<3>
  199  VSS86  POWER  = GND
  200  \dqs9_a_c||tdqs9_a_c\  BI  = M_G_CPU1_SA_DQS_DN<9>
  201  \dqs9_a_t||tdqs9_a_t\  BI  = M_G_CPU1_SA_DQS_DP<9>
  202  VSS87  POWER  = GND
  203  CB6_A  BI  = M_G_CPU1_SA_CB<6>
  204  VSS88  POWER  = GND
  205  CB7_A  BI  = M_G_CPU1_SA_CB<7>
  206  VSS89  POWER  = GND
  207  RESET_N  IN  = RST_M_GH_CPU1_FPGA_N
  208  VSS90  POWER  = GND
  209  CS1_A_N  IN  = M_G_CPU1_SA_CS_N<1>
  210  VSS91  POWER  = GND
  211  CA1_A  IN  = M_G_CPU1_SA_CA<1>
  212  VSS92  POWER  = GND
  213  CA3_A  IN  = M_G_CPU1_SA_CA<3>
  214  VSS93  POWER  = GND
  215  CA5_A  IN  = M_G_CPU1_SA_CA<5>
  216  VSS94  POWER  = GND
  217  CK_T  IN  = M_G_CPU1_CLK_DP<0>
  218  CK_C  IN  = M_G_CPU1_CLK_DN<0>
  219  VSS95  POWER  = GND
  220  RFU4  TRI  = TP_CHG_CPU1_DIMM1_FRU_4
  221  CA1_B  IN  = M_G_CPU1_SB_CA<1>
  222  VSS96  POWER  = GND
  223  CA3_B  IN  = M_G_CPU1_SB_CA<3>
  224  VSS97  POWER  = GND
  225  CA5_B  IN  = M_G_CPU1_SB_CA<5>
  226  VSS98  POWER  = GND
  227  PAR_B  IN  = M_G_CPU1_SB_PAR
  228  VSS99  POWER  = GND
  229  CS1_B_N  IN  = M_G_CPU1_SB_CS_N<1>
  230  VSS100  POWER  = GND
  231  RFU5  TRI  = TP_CHG_CPU1_DIMM1_FRU_5
  232  RFU6  TRI  = TP_CHG_CPU1_DIMM1_FRU_6
  233  VSS101  POWER  = GND
  234  CB6_B  BI  = M_G_CPU1_SB_CB<6>
  235  VSS102  POWER  = GND
  236  CB7_B  BI  = M_G_CPU1_SB_CB<7>
  237  VSS103  POWER  = GND
  238  DQS4_B_C  BI  = M_G_CPU1_SB_DQS_DN<4>
  239  DQS4_B_T  BI  = M_G_CPU1_SB_DQS_DP<4>
  240  VSS104  POWER  = GND
  241  CB2_B  BI  = M_G_CPU1_SB_CB<2>
  242  VSS105  POWER  = GND
  243  CB3_B  BI  = M_G_CPU1_SB_CB<3>
  244  VSS106  POWER  = GND
  245  DQ2_B  BI  = M_G_CPU1_SB_DQ<2>
  246  VSS107  POWER  = GND
  247  DQ3_B  BI  = M_G_CPU1_SB_DQ<3>
  248  VSS108  POWER  = GND
  249  \dqs5_b_c||tdqs5_b_c\  BI  = M_G_CPU1_SB_DQS_DN<5>
  250  \dqs5_b_t||tdqs5_b_t\  BI  = M_G_CPU1_SB_DQS_DP<5>
  251  VSS109  POWER  = GND
  252  DQ6_B  BI  = M_G_CPU1_SB_DQ<6>
  253  VSS110  POWER  = GND
  254  DQ7_B  BI  = M_G_CPU1_SB_DQ<7>
  255  VSS111  POWER  = GND
  256  DQ10_B  BI  = M_G_CPU1_SB_DQ<10>
  257  VSS112  POWER  = GND
  258  DQ11_B  BI  = M_G_CPU1_SB_DQ<11>
  259  VSS113  POWER  = GND
  260  \dqs6_b_c||tdqs6_b_c\  BI  = M_G_CPU1_SB_DQS_DN<6>
  261  \dqs6_b_t||tdqs6_b_t\  BI  = M_G_CPU1_SB_DQS_DP<6>
  262  VSS114  POWER  = GND
  263  DQ14_B  BI  = M_G_CPU1_SB_DQ<14>
  264  VSS115  POWER  = GND
  265  DQ15_B  BI  = M_G_CPU1_SB_DQ<15>
  266  VSS116  POWER  = GND
  267  DQ18_B  BI  = M_G_CPU1_SB_DQ<18>
  268  VSS117  POWER  = GND
  269  DQ19_B  BI  = M_G_CPU1_SB_DQ<19>
  270  VSS118  POWER  = GND
  271  \dqs7_b_c||tdqs7_b_c\  BI  = M_G_CPU1_SB_DQS_DN<7>
  272  \dqs7_b_t||tdqs7_b_t\  BI  = M_G_CPU1_SB_DQS_DP<7>
  273  VSS119  POWER  = GND
  274  DQ22_B  BI  = M_G_CPU1_SB_DQ<22>
  275  VSS120  POWER  = GND
  276  DQ23_B  BI  = M_G_CPU1_SB_DQ<23>
  277  VSS121  POWER  = GND
  278  DQ26_B  BI  = M_G_CPU1_SB_DQ<26>
  279  VSS122  POWER  = GND
  280  DQ27_B  BI  = M_G_CPU1_SB_DQ<27>
  281  VSS123  POWER  = GND
  282  \dqs8_b_c||tdqs8_b_c\  BI  = M_G_CPU1_SB_DQS_DN<8>
  283  \dqs8_b_t||tdqs8_b_t\  BI  = M_G_CPU1_SB_DQS_DP<8>
  284  VSS124  POWER  = GND
  285  DQ30_B  BI  = M_G_CPU1_SB_DQ<30>
  286  VSS125  POWER  = GND
  287  DQ31_B  BI  = M_G_CPU1_SB_DQ<31>
  288  VSS126  POWER  = GND
  G1  G1  POWER  = GND
  G2  G2  POWER  = GND
  G3  G3  POWER  = GND
